(kicad_pcb
	(version 20260206)
	(generator "pcbnew")
	(generator_version "10.0")
	(general
		(thickness 1.21888)
		(legacy_teardrops no)
	)
	(paper "A4")
	(title_block
		(title "timecard-v9 — TimeCard-DC-V9_EXP.PcbDoc")
		(comment 1 "Time Appliance Project (Time Card) / footprints 258-267 of 402")
	)
	(layers
		(0 "F.Cu" signal "TOP")
		(4 "In1.Cu" signal "SGND")
		(6 "In2.Cu" signal "IN1")
		(8 "In3.Cu" signal "IN2")
		(10 "In4.Cu" signal "SGND1")
		(2 "B.Cu" signal "BOTTOM")
		(9 "F.Adhes" user "F.Adhesive")
		(11 "B.Adhes" user "B.Adhesive")
		(13 "F.Paste" user "Top Paste")
		(15 "B.Paste" user "Bottom Paste")
		(5 "F.SilkS" user "Top Overlay")
		(7 "B.SilkS" user "Bottom Overlay")
		(1 "F.Mask" user "Top Solder")
		(3 "B.Mask" user "Bottom Solder")
		(17 "Dwgs.User" user "User.Drawings")
		(19 "Cmts.User" user "User.Comments")
		(21 "Eco1.User" user "User.Eco1")
		(23 "Eco2.User" user "User.Eco2")
		(25 "Edge.Cuts" user)
		(27 "Margin" user)
		(31 "F.CrtYd" user "Top Courtyard")
		(29 "B.CrtYd" user "Bottom Courtyard")
		(35 "F.Fab" user "Top Component Center")
		(33 "B.Fab" user "Bottom Component Center")
	)
	(footprint "Vault:FP-0402-L_1_0_1-W_0_5_0_1-IPC_C"
		(layer "B.Cu")
		(at 110.66622 54.1145 -90)
		(property "Reference" "C109"
			(at 2.8049 -0.182301 90)
			(unlocked yes)
			(layer "B.SilkS")
			(effects
				(font
					(size 0.762 0.762)
					(thickness 0.2032)
				)
				(justify mirror)
			)
		)
		(property "Value" "0.1uF_25V_0402"
			(at -2.465551 -9.813805 180)
			(unlocked yes)
			(layer "B.SilkS")
			(hide yes)
			(effects
				(font
					(size 0.762 0.762)
					(thickness 0.2032)
				)
				(justify mirror)
			)
		)
		(sheetname "11-M2_RCB_MUX")
		(sheetfile "11-M2_RCB_MUX.kicad_sch")
		(duplicate_pad_numbers_are_jumpers no)
		(fp_line
			(start 0.65607 0.7)
			(end -0.65607 0.7)
			(stroke
				(width 0.2)
				(type solid)
			)
			(layer "B.SilkS")
		)
		(fp_line
			(start 0.65607 -0.7)
			(end -0.65607 -0.7)
			(stroke
				(width 0.2)
				(type solid)
			)
			(layer "B.SilkS")
		)
		(fp_line
			(start -0.75607 0.4)
			(end -0.75607 -0.4)
			(stroke
				(width 0.2)
				(type solid)
			)
			(layer "B.CrtYd")
		)
		(fp_line
			(start 0.75607 0.4)
			(end -0.75607 0.4)
			(stroke
				(width 0.2)
				(type solid)
			)
			(layer "B.CrtYd")
		)
		(fp_line
			(start 0.75607 0.4)
			(end 0.75607 -0.4)
			(stroke
				(width 0.2)
				(type solid)
			)
			(layer "B.CrtYd")
		)
		(fp_line
			(start 0.75607 -0.4)
			(end -0.75607 -0.4)
			(stroke
				(width 0.2)
				(type solid)
			)
			(layer "B.CrtYd")
		)
		(fp_line
			(start 0 0.5)
			(end 0 -0.5)
			(stroke
				(width 0.1)
				(type solid)
			)
			(layer "B.Fab")
		)
		(fp_line
			(start -0.75607 0.4)
			(end -0.75607 -0.4)
			(stroke
				(width 0.2)
				(type solid)
			)
			(layer "B.Fab")
		)
		(fp_line
			(start 0.75607 0.4)
			(end -0.75607 0.4)
			(stroke
				(width 0.2)
				(type solid)
			)
			(layer "B.Fab")
		)
		(fp_line
			(start 0.75607 0.4)
			(end 0.75607 -0.4)
			(stroke
				(width 0.2)
				(type solid)
			)
			(layer "B.Fab")
		)
		(fp_line
			(start 0.5 0)
			(end -0.5 0)
			(stroke
				(width 0.1)
				(type solid)
			)
			(layer "B.Fab")
		)
		(fp_line
			(start 0.75607 -0.4)
			(end -0.75607 -0.4)
			(stroke
				(width 0.2)
				(type solid)
			)
			(layer "B.Fab")
		)
		(fp_text user "${REFERENCE}"
			(at -0.00001 -0.09601 90)
			(unlocked yes)
			(layer "B.Fab")
			(effects
				(font
					(face "Arial")
					(size 0.63 0.63)
					(thickness 0.1)
				)
				(justify left bottom mirror)
			)
		)
		(pad "1" smd rect
			(at -0.36554 0 270)
			(size 0.58106 0.51213)
			(layers "B.Cu" "B.Mask" "B.Paste")
			(net "+3.3V")
			(solder_mask_margin 0)
			(solder_paste_margin 0)
		)
		(pad "2" smd rect
			(at 0.36554 0 270)
			(size 0.58106 0.51213)
			(layers "B.Cu" "B.Mask" "B.Paste")
			(net "GND")
			(solder_mask_margin 0)
			(solder_paste_margin 0)
		)
	)
	(footprint "Vault:CAPC1608X87X45ML20T05"
		(layer "B.Cu")
		(at 121.7216 83.5162 180)
		(property "Reference" "C24"
			(at 0.2286 1.373079 0)
			(unlocked yes)
			(layer "B.SilkS")
			(effects
				(font
					(size 0.762 0.762)
					(thickness 0.2286)
				)
				(justify mirror)
			)
		)
		(property "Value" "0.1uF"
			(at 2.069035 -2.630671 0)
			(unlocked yes)
			(layer "B.SilkS")
			(hide yes)
			(effects
				(font
					(size 0.762 0.762)
					(thickness 0.2286)
				)
				(justify mirror)
			)
		)
		(sheetname "06-MAC")
		(sheetfile "06-MAC.kicad_sch")
		(duplicate_pad_numbers_are_jumpers no)
		(pad "1" smd rect
			(at -0.7 0 90)
			(size 1.1 1.05)
			(layers "B.Cu" "B.Mask" "B.Paste")
			(net "+3.3V")
		)
		(pad "2" smd rect
			(at 0.7 0 90)
			(size 1.1 1.05)
			(layers "B.Cu" "B.Mask" "B.Paste")
			(net "GND")
		)
	)
	(footprint "Vault:FP-C1005-050-0_05-IPC_A"
		(layer "B.Cu")
		(at 100.8216 59.2162 180)
		(property "Reference" "C3"
			(at -0.6 1.106655 0)
			(unlocked yes)
			(layer "B.SilkS")
			(effects
				(font
					(size 0.762 0.762)
					(thickness 0.2286)
				)
				(justify left bottom mirror)
			)
		)
		(property "Value" "2.2uF_16V_0402"
			(at 0.7365 8.683165 0)
			(unlocked yes)
			(layer "B.SilkS")
			(hide yes)
			(effects
				(font
					(size 0.762 0.762)
					(thickness 0.2286)
				)
				(justify left bottom mirror)
			)
		)
		(sheetname "03-POWER")
		(sheetfile "03-POWER.kicad_sch")
		(duplicate_pad_numbers_are_jumpers no)
		(fp_line
			(start 0.83624 0.73624)
			(end -0.83624 0.73624)
			(stroke
				(width 0.2)
				(type solid)
			)
			(layer "B.SilkS")
		)
		(fp_line
			(start 0.83624 -0.73624)
			(end -0.83624 -0.73624)
			(stroke
				(width 0.2)
				(type solid)
			)
			(layer "B.SilkS")
		)
		(fp_line
			(start 1.03624 0.53624)
			(end -1.03624 0.53624)
			(stroke
				(width 0.2)
				(type solid)
			)
			(layer "B.CrtYd")
		)
		(fp_line
			(start 1.03624 -0.53624)
			(end 1.03624 0.53624)
			(stroke
				(width 0.2)
				(type solid)
			)
			(layer "B.CrtYd")
		)
		(fp_line
			(start 1.03624 -0.53624)
			(end -1.03624 -0.53624)
			(stroke
				(width 0.2)
				(type solid)
			)
			(layer "B.CrtYd")
		)
		(fp_line
			(start -1.03624 -0.53624)
			(end -1.03624 0.53624)
			(stroke
				(width 0.2)
				(type solid)
			)
			(layer "B.CrtYd")
		)
		(fp_line
			(start 1.03624 0.53624)
			(end -1.03624 0.53624)
			(stroke
				(width 0.2)
				(type solid)
			)
			(layer "B.Fab")
		)
		(fp_line
			(start 1.03624 -0.53624)
			(end 1.03624 0.53624)
			(stroke
				(width 0.2)
				(type solid)
			)
			(layer "B.Fab")
		)
		(fp_line
			(start 1.03624 -0.53624)
			(end -1.03624 -0.53624)
			(stroke
				(width 0.2)
				(type solid)
			)
			(layer "B.Fab")
		)
		(fp_line
			(start 0.5 0)
			(end -0.5 0)
			(stroke
				(width 0.1)
				(type solid)
			)
			(layer "B.Fab")
		)
		(fp_line
			(start 0 -0.5)
			(end 0 0.5)
			(stroke
				(width 0.1)
				(type solid)
			)
			(layer "B.Fab")
		)
		(fp_line
			(start -1.03624 -0.53624)
			(end -1.03624 0.53624)
			(stroke
				(width 0.2)
				(type solid)
			)
			(layer "B.Fab")
		)
		(fp_text user "${REFERENCE}"
			(at -0.00001 -0.09602 360)
			(unlocked yes)
			(layer "B.Fab")
			(effects
				(font
					(face "Arial")
					(size 0.63 0.63)
					(thickness 0.1)
				)
				(justify left bottom mirror)
			)
		)
		(pad "1" smd rect
			(at -0.46658 0 180)
			(size 0.73933 0.67248)
			(layers "B.Cu" "B.Mask" "B.Paste")
			(net "P5V_MUN_VCC")
			(solder_mask_margin 0)
			(solder_paste_margin 0)
		)
		(pad "2" smd rect
			(at 0.46657 0 180)
			(size 0.73933 0.67248)
			(layers "B.Cu" "B.Mask" "B.Paste")
			(net "GND")
			(solder_mask_margin 0)
			(solder_paste_margin 0)
		)
	)
	(footprint "Vault:RESC1005X40X25LL05T05"
		(layer "B.Cu")
		(at 112.25573 84.8412 -90)
		(property "Reference" "R57"
			(at -4.7964 -4.692791 90)
			(unlocked yes)
			(layer "B.SilkS")
			(effects
				(font
					(size 0.762 0.762)
					(thickness 0.2286)
				)
				(justify mirror)
			)
		)
		(property "Value" "4.7K_0402"
			(at -3.024391 -2.374035 180)
			(unlocked yes)
			(layer "B.SilkS")
			(hide yes)
			(effects
				(font
					(size 0.762 0.762)
					(thickness 0.2286)
				)
				(justify mirror)
			)
		)
		(sheetname "05-GPS_IMU_SENSORS")
		(sheetfile "05-GPS_IMU_SENSORS.kicad_sch")
		(duplicate_pad_numbers_are_jumpers no)
		(pad "1" smd rect
			(at -0.4 0 180)
			(size 0.45 0.45)
			(layers "B.Cu" "B.Mask" "B.Paste")
			(net "BNO_P3V3")
		)
		(pad "2" smd rect
			(at 0.4 0 180)
			(size 0.45 0.45)
			(layers "B.Cu" "B.Mask" "B.Paste")
			(net "NetR57_2")
		)
	)
	(footprint "Vault:RESC1005X40X25LL05T05"
		(layer "B.Cu")
		(at 113.78072 89.7662)
		(property "Reference" "R53"
			(at 0.86948 1.123069 180)
			(unlocked yes)
			(layer "B.SilkS")
			(effects
				(font
					(size 0.762 0.762)
					(thickness 0.2286)
				)
				(justify mirror)
			)
		)
		(property "Value" "4.7K_0402"
			(at -3.024391 -2.374045 270)
			(unlocked yes)
			(layer "B.SilkS")
			(hide yes)
			(effects
				(font
					(size 0.762 0.762)
					(thickness 0.2286)
				)
				(justify mirror)
			)
		)
		(sheetname "05-GPS_IMU_SENSORS")
		(sheetfile "05-GPS_IMU_SENSORS.kicad_sch")
		(duplicate_pad_numbers_are_jumpers no)
		(pad "1" smd rect
			(at -0.4 0 270)
			(size 0.45 0.45)
			(layers "B.Cu" "B.Mask" "B.Paste")
			(net "NetR53_1")
		)
		(pad "2" smd rect
			(at 0.40001 0 270)
			(size 0.45 0.45)
			(layers "B.Cu" "B.Mask" "B.Paste")
			(net "BNO_P3V3")
		)
	)
	(footprint "Vault:FP-0402-L_1_0_1-W_0_5_0_1-IPC_C"
		(layer "B.Cu")
		(at 228.16036 113.8162)
		(property "Reference" "C92"
			(at -0.13771 -1.704879 0)
			(unlocked yes)
			(layer "B.SilkS")
			(effects
				(font
					(size 0.762 0.762)
					(thickness 0.2286)
				)
				(justify mirror)
			)
		)
		(property "Value" "0.1uF_25V_0402"
			(at -2.465551 -9.839215 270)
			(unlocked yes)
			(layer "B.SilkS")
			(hide yes)
			(effects
				(font
					(size 0.762 0.762)
					(thickness 0.2286)
				)
				(justify mirror)
			)
		)
		(sheetname "09-USBUart_PPSMUX_UARTMUX")
		(sheetfile "09-USBUart_PPSMUX_UARTMUX.kicad_sch")
		(duplicate_pad_numbers_are_jumpers no)
		(fp_line
			(start -0.65606 -0.7)
			(end 0.65607 -0.7)
			(stroke
				(width 0.2)
				(type solid)
			)
			(layer "B.SilkS")
		)
		(fp_line
			(start -0.65606 0.7)
			(end 0.65607 0.7)
			(stroke
				(width 0.2)
				(type solid)
			)
			(layer "B.SilkS")
		)
		(fp_line
			(start -0.75606 -0.4)
			(end 0.75607 -0.4)
			(stroke
				(width 0.2)
				(type solid)
			)
			(layer "B.CrtYd")
		)
		(fp_line
			(start -0.75606 0.4)
			(end -0.75606 -0.4)
			(stroke
				(width 0.2)
				(type solid)
			)
			(layer "B.CrtYd")
		)
		(fp_line
			(start -0.75606 0.4)
			(end 0.75607 0.4)
			(stroke
				(width 0.2)
				(type solid)
			)
			(layer "B.CrtYd")
		)
		(fp_line
			(start 0.75607 0.4)
			(end 0.75607 -0.4)
			(stroke
				(width 0.2)
				(type solid)
			)
			(layer "B.CrtYd")
		)
		(fp_line
			(start -0.75606 -0.4)
			(end 0.75607 -0.4)
			(stroke
				(width 0.2)
				(type solid)
			)
			(layer "B.Fab")
		)
		(fp_line
			(start -0.75606 0.4)
			(end -0.75606 -0.4)
			(stroke
				(width 0.2)
				(type solid)
			)
			(layer "B.Fab")
		)
		(fp_line
			(start -0.75606 0.4)
			(end 0.75607 0.4)
			(stroke
				(width 0.2)
				(type solid)
			)
			(layer "B.Fab")
		)
		(fp_line
			(start -0.5 0)
			(end 0.5 0)
			(stroke
				(width 0.1)
				(type solid)
			)
			(layer "B.Fab")
		)
		(fp_line
			(start 0 0.5)
			(end 0 -0.5)
			(stroke
				(width 0.1)
				(type solid)
			)
			(layer "B.Fab")
		)
		(fp_line
			(start 0.75607 0.4)
			(end 0.75607 -0.4)
			(stroke
				(width 0.2)
				(type solid)
			)
			(layer "B.Fab")
		)
		(fp_text user "${REFERENCE}"
			(at -0.00001 -0.09601 180)
			(unlocked yes)
			(layer "B.Fab")
			(effects
				(font
					(face "Arial")
					(size 0.63 0.63)
					(thickness 0.1)
				)
				(justify left bottom mirror)
			)
		)
		(pad "1" smd rect
			(at -0.36553 0)
			(size 0.58106 0.51213)
			(layers "B.Cu" "B.Mask" "B.Paste")
			(net "NetC92_1")
			(solder_mask_margin 0)
			(solder_paste_margin 0)
		)
		(pad "2" smd rect
			(at 0.36554 0)
			(size 0.58106 0.51213)
			(layers "B.Cu" "B.Mask" "B.Paste")
			(net "GND")
			(solder_mask_margin 0)
			(solder_paste_margin 0)
		)
	)
	(footprint "Capacitors:CAPC1005X06N"
		(layer "B.Cu")
		(at 133.5746 151.7886 90)
		(property "Reference" "C49"
			(at 2.41349 -0.156655 270)
			(unlocked yes)
			(layer "B.SilkS")
			(effects
				(font
					(size 0.762 0.762)
					(thickness 0.2286)
				)
				(justify left bottom mirror)
			)
		)
		(property "Value" "CAP_0402_0.1UF_50V"
			(at -3.382645 0.2921 0)
			(unlocked yes)
			(layer "B.SilkS")
			(hide yes)
			(effects
				(font
					(size 0.762 0.762)
					(thickness 0.2286)
				)
				(justify left bottom mirror)
			)
		)
		(sheetname "04-PCIe_JTAG")
		(sheetfile "04-PCIe_JTAG.kicad_sch")
		(duplicate_pad_numbers_are_jumpers no)
		(pad "1" smd rect
			(at -0.43 0)
			(size 0.64 0.68)
			(layers "B.Cu" "B.Mask" "B.Paste")
			(net "NetC49_1")
		)
		(pad "2" smd rect
			(at 0.43 0)
			(size 0.64 0.68)
			(layers "B.Cu" "B.Mask" "B.Paste")
			(net "PCIE_TX1_N")
		)
	)
	(footprint "Capacitors:CAPC1005X06N"
		(layer "B.Cu")
		(at 128.6724 151.7886 90)
		(property "Reference" "C47"
			(at 2.41349 0.097345 270)
			(unlocked yes)
			(layer "B.SilkS")
			(effects
				(font
					(size 0.762 0.762)
					(thickness 0.2286)
				)
				(justify left bottom mirror)
			)
		)
		(property "Value" "CAP_0402_0.1UF_50V"
			(at -3.382645 0.2921 0)
			(unlocked yes)
			(layer "B.SilkS")
			(hide yes)
			(effects
				(font
					(size 0.762 0.762)
					(thickness 0.2286)
				)
				(justify left bottom mirror)
			)
		)
		(sheetname "04-PCIe_JTAG")
		(sheetfile "04-PCIe_JTAG.kicad_sch")
		(duplicate_pad_numbers_are_jumpers no)
		(pad "1" smd rect
			(at -0.43 0)
			(size 0.64 0.68)
			(layers "B.Cu" "B.Mask" "B.Paste")
			(net "NetC47_1")
		)
		(pad "2" smd rect
			(at 0.43 0)
			(size 0.64 0.68)
			(layers "B.Cu" "B.Mask" "B.Paste")
			(net "PCIE_TX0_N")
		)
	)
	(footprint "Vault:FP-C1005-050-0_05-IPC_A"
		(layer "B.Cu")
		(at 96.5216 67.0162 -90)
		(property "Reference" "C16"
			(at 3.3 0.493345 270)
			(unlocked yes)
			(layer "B.SilkS")
			(effects
				(font
					(size 0.762 0.762)
					(thickness 0.2286)
				)
				(justify left bottom mirror)
			)
		)
		(property "Value" "2.2uF_16V_0402"
			(at 1.941545 14.9177 0)
			(unlocked yes)
			(layer "B.SilkS")
			(hide yes)
			(effects
				(font
					(size 0.762 0.762)
					(thickness 0.2286)
				)
				(justify left bottom mirror)
			)
		)
		(sheetname "03-POWER")
		(sheetfile "03-POWER.kicad_sch")
		(duplicate_pad_numbers_are_jumpers no)
		(fp_line
			(start 0.83624 0.73624)
			(end -0.83624 0.73624)
			(stroke
				(width 0.2)
				(type solid)
			)
			(layer "B.SilkS")
		)
		(fp_line
			(start 0.83624 -0.73624)
			(end -0.83624 -0.73624)
			(stroke
				(width 0.2)
				(type solid)
			)
			(layer "B.SilkS")
		)
		(fp_line
			(start -1.03624 0.53624)
			(end -1.03624 -0.53624)
			(stroke
				(width 0.2)
				(type solid)
			)
			(layer "B.CrtYd")
		)
		(fp_line
			(start 1.03623 0.53624)
			(end -1.03624 0.53624)
			(stroke
				(width 0.2)
				(type solid)
			)
			(layer "B.CrtYd")
		)
		(fp_line
			(start 1.03623 0.53624)
			(end 1.03623 -0.53624)
			(stroke
				(width 0.2)
				(type solid)
			)
			(layer "B.CrtYd")
		)
		(fp_line
			(start 1.03623 -0.53624)
			(end -1.03624 -0.53624)
			(stroke
				(width 0.2)
				(type solid)
			)
			(layer "B.CrtYd")
		)
		(fp_line
			(start -1.03624 0.53624)
			(end -1.03624 -0.53624)
			(stroke
				(width 0.2)
				(type solid)
			)
			(layer "B.Fab")
		)
		(fp_line
			(start 1.03623 0.53624)
			(end -1.03624 0.53624)
			(stroke
				(width 0.2)
				(type solid)
			)
			(layer "B.Fab")
		)
		(fp_line
			(start 1.03623 0.53624)
			(end 1.03623 -0.53624)
			(stroke
				(width 0.2)
				(type solid)
			)
			(layer "B.Fab")
		)
		(fp_line
			(start 0 0.5)
			(end 0 -0.5)
			(stroke
				(width 0.1)
				(type solid)
			)
			(layer "B.Fab")
		)
		(fp_line
			(start 0.5 0)
			(end -0.5 0)
			(stroke
				(width 0.1)
				(type solid)
			)
			(layer "B.Fab")
		)
		(fp_line
			(start 1.03623 -0.53624)
			(end -1.03624 -0.53624)
			(stroke
				(width 0.2)
				(type solid)
			)
			(layer "B.Fab")
		)
		(fp_text user "${REFERENCE}"
			(at -0.00001 -0.09601 90)
			(unlocked yes)
			(layer "B.Fab")
			(effects
				(font
					(face "Arial")
					(size 0.63 0.63)
					(thickness 0.1)
				)
				(justify left bottom mirror)
			)
		)
		(pad "1" smd rect
			(at -0.46658 0 270)
			(size 0.73933 0.67248)
			(layers "B.Cu" "B.Mask" "B.Paste")
			(net "+5.0V")
			(solder_mask_margin 0)
			(solder_paste_margin 0)
		)
		(pad "2" smd rect
			(at 0.46657 0 270)
			(size 0.73933 0.67248)
			(layers "B.Cu" "B.Mask" "B.Paste")
			(net "GND")
			(solder_mask_margin 0)
			(solder_paste_margin 0)
		)
	)
	(footprint "Vault:RESC1005X40X25NL10T10"
		(layer "B.Cu")
		(at 89.9216 54.9162 180)
		(property "Reference" "R59"
			(at 0.2786 1.123069 0)
			(unlocked yes)
			(layer "B.SilkS")
			(effects
				(font
					(size 0.762 0.762)
					(thickness 0.2286)
				)
				(justify mirror)
			)
		)
		(property "Value" "10K_1%_0402"
			(at -2.884671 -8.544305 90)
			(unlocked yes)
			(layer "B.SilkS")
			(hide yes)
			(effects
				(font
					(size 0.762 0.762)
					(thickness 0.2286)
				)
				(justify mirror)
			)
		)
		(sheetname "03-POWER")
		(sheetfile "03-POWER.kicad_sch")
		(duplicate_pad_numbers_are_jumpers no)
		(pad "1" smd rect
			(at -0.425 0 90)
			(size 0.6 0.65)
			(layers "B.Cu" "B.Mask" "B.Paste")
			(net "GND")
		)
		(pad "2" smd rect
			(at 0.425 0 90)
			(size 0.6 0.65)
			(layers "B.Cu" "B.Mask" "B.Paste")
			(net "NetR9_2")
		)
	)
)
